(kicad_pcb
	(version 20260206)
	(generator "pcbnew")
	(generator_version "10.0")
	(general
		(thickness 1.6)
		(legacy_teardrops no)
	)
	(paper "A4")
	(title_block
		(title "03242023_DA0F0TMBIJ0_F0T_Motherboard_J_brd_V01_OCP.brd")
		(comment 1 "Grand Teton / footprints 236-241 of 6105")
	)
	(layers
		(0 "F.Cu" signal "TOP")
		(4 "In1.Cu" signal "GND")
		(6 "In2.Cu" signal "IN1")
		(8 "In3.Cu" signal "GND1")
		(10 "In4.Cu" signal "IN2")
		(12 "In5.Cu" signal "GND2")
		(14 "In6.Cu" signal "IN3")
		(16 "In7.Cu" signal "GND3")
		(18 "In8.Cu" signal "VCC")
		(20 "In9.Cu" signal "VCC1")
		(22 "In10.Cu" signal "GND4")
		(24 "In11.Cu" signal "IN4")
		(26 "In12.Cu" signal "GND5")
		(28 "In13.Cu" signal "IN5")
		(30 "In14.Cu" signal "GND6")
		(32 "In15.Cu" signal "IN6")
		(34 "In16.Cu" signal "GND7")
		(2 "B.Cu" signal "BOTTOM")
		(9 "F.Adhes" user "F.Adhesive")
		(11 "B.Adhes" user "B.Adhesive")
		(13 "F.Paste" user "Package Geometry/Pastemask Top")
		(15 "B.Paste" user "Package Geometry/Pastemask Bottom")
		(5 "F.SilkS" user "Ref Des/Silkscreen Top")
		(7 "B.SilkS" user "Ref Des/Silkscreen Bottom")
		(1 "F.Mask" user "Board Geometry/Soldermask Top")
		(3 "B.Mask" user "Board Geometry/Soldermask Bottom")
		(17 "Dwgs.User" user "User.Drawings")
		(19 "Cmts.User" user "User.Comments")
		(21 "Eco1.User" user "User.Eco1")
		(23 "Eco2.User" user "User.Eco2")
		(25 "Edge.Cuts" user "Board Geometry/Outline")
		(27 "Margin" user)
		(31 "F.CrtYd" user "Package Geometry/Place Bound Top")
		(29 "B.CrtYd" user "Package Geometry/Place Bound Bottom")
		(35 "F.Fab" user "Ref Des/Assembly Top")
		(33 "B.Fab" user "Ref Des/Assembly Bottom")
	)
	(footprint ""
		(layer "F.Cu")
		(at 260.096508 -398.78 90)
		(property "Reference" "PPQ6"
			(at -8.10514 -1.938528 0)
			(unlocked yes)
			(layer "F.SilkS")
			(effects
				(font
					(size 0.7874 0.5842)
					(thickness 0.1524)
				)
				(justify left)
			)
		)
		(property "Value" ""
			(at 0 0 90)
			(layer "F.Fab")
			(effects
				(font
					(size 1.27 1.27)
				)
			)
		)
		(duplicate_pad_numbers_are_jumpers no)
		(fp_line
			(start 2.350008 -2.649982)
			(end 2.350008 -2.4892)
			(stroke
				(width 0.1524)
				(type default)
			)
			(layer "F.SilkS")
		)
		(fp_line
			(start -2.350008 -2.649982)
			(end 2.350008 -2.649982)
			(stroke
				(width 0.1524)
				(type default)
			)
			(layer "F.SilkS")
		)
		(fp_line
			(start -2.350008 -2.4384)
			(end -2.350008 -2.649982)
			(stroke
				(width 0.1524)
				(type default)
			)
			(layer "F.SilkS")
		)
		(fp_line
			(start 2.350008 2.4892)
			(end 2.350008 2.649982)
			(stroke
				(width 0.1524)
				(type default)
			)
			(layer "F.SilkS")
		)
		(fp_line
			(start 2.350008 2.649982)
			(end -2.350008 2.649982)
			(stroke
				(width 0.1524)
				(type default)
			)
			(layer "F.SilkS")
		)
		(fp_line
			(start -2.350008 2.649982)
			(end -2.350008 2.413)
			(stroke
				(width 0.1524)
				(type default)
			)
			(layer "F.SilkS")
		)
		(fp_poly
			(pts
				(xy -3.717544 -1.905) (xy -4.758944 -2.3241) (xy -4.758944 -1.524)
			)
			(stroke
				(width 0)
				(type default)
			)
			(fill yes)
			(layer "F.SilkS")
		)
		(fp_line
			(start 2.350008 -2.649982)
			(end 2.350008 2.649982)
			(stroke
				(width 0.1)
				(type default)
			)
			(layer "F.Fab")
		)
		(fp_line
			(start -2.350008 -2.649982)
			(end 2.350008 -2.649982)
			(stroke
				(width 0.1)
				(type default)
			)
			(layer "F.Fab")
		)
		(fp_line
			(start 2.350008 2.649982)
			(end -2.350008 2.649982)
			(stroke
				(width 0.1)
				(type default)
			)
			(layer "F.Fab")
		)
		(fp_line
			(start -2.350008 2.649982)
			(end -2.350008 -2.649982)
			(stroke
				(width 0.1)
				(type default)
			)
			(layer "F.Fab")
		)
		(fp_poly
			(pts
				(xy -3.717544 -1.905) (xy -4.758944 -2.3241) (xy -4.758944 -1.524)
			)
			(stroke
				(width 0)
				(type default)
			)
			(fill yes)
			(layer "F.Fab")
		)
		(pad "1" smd rect
			(at -2.999994 -1.905)
			(size 0.7112 1.1684)
			(layers "F.Cu" "F.Mask" "F.Paste")
			(net "P12V_AUX")
		)
		(pad "2" smd rect
			(at -2.999994 -0.635)
			(size 0.7112 1.1684)
			(layers "F.Cu" "F.Mask" "F.Paste")
			(net "P12V_AUX")
		)
		(pad "3" smd rect
			(at -2.999994 0.635)
			(size 0.7112 1.1684)
			(layers "F.Cu" "F.Mask" "F.Paste")
			(net "P12V_AUX")
		)
		(pad "4" smd rect
			(at -2.999994 1.905)
			(size 0.7112 1.1684)
			(layers "F.Cu" "F.Mask" "F.Paste")
			(net "P12V_HSC_GATE_G2")
		)
		(pad "5" smd circle
			(at 0.925068 0)
			(size 0 0)
			(layers "F.Cu" "F.Mask" "F.Paste")
			(net "P12V_MAIN_R")
		)
		(zone
			(layer "F.Cu")
			(hatch none 0.5)
			(connect_pads
				(clearance 0)
			)
			(min_thickness 0.25)
			(keepout
				(tracks not_allowed)
				(vias allowed)
				(pads allowed)
				(copperpour not_allowed)
				(footprints allowed)
			)
			(placement
				(enabled no)
				(sheetname "")
			)
			(fill
				(thermal_gap 0.5)
				(thermal_bridge_width 0.5)
				(island_removal_mode 0)
			)
			(polygon
				(pts
					(xy 257.937508 -397.3322) (xy 262.255508 -397.3322) (xy 262.738108 -397.3322) (xy 262.738108 -396.4305)
					(xy 257.454908 -396.4305) (xy 257.454908 -397.3322)
				)
			)
		)
	)
	(footprint ""
		(layer "F.Cu")
		(at 29.904182 -390.084818)
		(property "Reference" "R4655"
			(at 0 0 0)
			(layer "F.SilkS")
			(hide yes)
			(effects
				(font
					(size 1.27 1.27)
				)
			)
		)
		(property "Value" ""
			(at 0 0 0)
			(layer "F.Fab")
			(effects
				(font
					(size 1.27 1.27)
				)
			)
		)
		(duplicate_pad_numbers_are_jumpers no)
		(fp_line
			(start -0.7874 -0.4064)
			(end 0.7874 -0.4064)
			(stroke
				(width 0.1524)
				(type default)
			)
			(layer "F.SilkS")
		)
		(fp_line
			(start -0.7874 0.4064)
			(end -0.7874 -0.4064)
			(stroke
				(width 0.1524)
				(type default)
			)
			(layer "F.SilkS")
		)
		(fp_line
			(start 0.7874 -0.4064)
			(end 0.7874 0.4064)
			(stroke
				(width 0.1524)
				(type default)
			)
			(layer "F.SilkS")
		)
		(fp_line
			(start 0.7874 0.4064)
			(end -0.7874 0.4064)
			(stroke
				(width 0.1524)
				(type default)
			)
			(layer "F.SilkS")
		)
		(fp_line
			(start -0.67945 -0.305054)
			(end -0.12065 -0.305054)
			(stroke
				(width 0.1)
				(type default)
			)
			(layer "F.Fab")
		)
		(fp_line
			(start -0.67945 0.3048)
			(end -0.67945 -0.305054)
			(stroke
				(width 0.1)
				(type default)
			)
			(layer "F.Fab")
		)
		(fp_line
			(start -0.12065 -0.305054)
			(end -0.12065 -0.2794)
			(stroke
				(width 0.1)
				(type default)
			)
			(layer "F.Fab")
		)
		(fp_line
			(start -0.12065 -0.2794)
			(end 0.12065 -0.2794)
			(stroke
				(width 0.1)
				(type default)
			)
			(layer "F.Fab")
		)
		(fp_line
			(start -0.12065 0.2794)
			(end -0.12065 0.3048)
			(stroke
				(width 0.1)
				(type default)
			)
			(layer "F.Fab")
		)
		(fp_line
			(start -0.12065 0.3048)
			(end -0.67945 0.3048)
			(stroke
				(width 0.1)
				(type default)
			)
			(layer "F.Fab")
		)
		(fp_line
			(start 0.120396 0.2794)
			(end -0.12065 0.2794)
			(stroke
				(width 0.1)
				(type default)
			)
			(layer "F.Fab")
		)
		(fp_line
			(start 0.120396 0.3048)
			(end 0.120396 0.2794)
			(stroke
				(width 0.1)
				(type default)
			)
			(layer "F.Fab")
		)
		(fp_line
			(start 0.12065 -0.3048)
			(end 0.67945 -0.3048)
			(stroke
				(width 0.1)
				(type default)
			)
			(layer "F.Fab")
		)
		(fp_line
			(start 0.12065 -0.2794)
			(end 0.12065 -0.3048)
			(stroke
				(width 0.1)
				(type default)
			)
			(layer "F.Fab")
		)
		(fp_line
			(start 0.67945 -0.3048)
			(end 0.67945 0.3048)
			(stroke
				(width 0.1)
				(type default)
			)
			(layer "F.Fab")
		)
		(fp_line
			(start 0.67945 0.3048)
			(end 0.120396 0.3048)
			(stroke
				(width 0.1)
				(type default)
			)
			(layer "F.Fab")
		)
		(pad "1" smd circle
			(at -0.40005 0)
			(size 0 0)
			(layers "F.Cu" "F.Mask" "F.Paste")
			(net "P3V3_AUX")
		)
		(pad "2" smd circle
			(at 0.40005 0)
			(size 0 0)
			(layers "F.Cu" "F.Mask" "F.Paste")
			(net "FM_P2E_BUF2_RXDET")
		)
	)
	(footprint ""
		(layer "F.Cu")
		(at 350.294956 -338.290662 -90)
		(property "Reference" "PC1355"
			(at 0 0 270)
			(layer "F.SilkS")
			(hide yes)
			(effects
				(font
					(size 1.27 1.27)
				)
			)
		)
		(property "Value" ""
			(at 0 0 270)
			(layer "F.Fab")
			(effects
				(font
					(size 1.27 1.27)
				)
			)
		)
		(duplicate_pad_numbers_are_jumpers no)
		(fp_line
			(start -0.7874 0.4064)
			(end -0.7874 -0.4064)
			(stroke
				(width 0.1524)
				(type default)
			)
			(layer "F.SilkS")
		)
		(fp_line
			(start 0.7874 0.4064)
			(end -0.7874 0.4064)
			(stroke
				(width 0.1524)
				(type default)
			)
			(layer "F.SilkS")
		)
		(fp_line
			(start -0.7874 -0.4064)
			(end 0.7874 -0.4064)
			(stroke
				(width 0.1524)
				(type default)
			)
			(layer "F.SilkS")
		)
		(fp_line
			(start 0.7874 -0.4064)
			(end 0.7874 0.4064)
			(stroke
				(width 0.1524)
				(type default)
			)
			(layer "F.SilkS")
		)
		(fp_line
			(start -0.67945 0.3048)
			(end -0.67945 -0.305054)
			(stroke
				(width 0.1)
				(type default)
			)
			(layer "F.Fab")
		)
		(fp_line
			(start -0.12065 0.3048)
			(end -0.67945 0.3048)
			(stroke
				(width 0.1)
				(type default)
			)
			(layer "F.Fab")
		)
		(fp_line
			(start 0.120396 0.3048)
			(end 0.120396 0.2794)
			(stroke
				(width 0.1)
				(type default)
			)
			(layer "F.Fab")
		)
		(fp_line
			(start 0.67945 0.3048)
			(end 0.120396 0.3048)
			(stroke
				(width 0.1)
				(type default)
			)
			(layer "F.Fab")
		)
		(fp_line
			(start -0.12065 0.2794)
			(end -0.12065 0.3048)
			(stroke
				(width 0.1)
				(type default)
			)
			(layer "F.Fab")
		)
		(fp_line
			(start 0.120396 0.2794)
			(end -0.12065 0.2794)
			(stroke
				(width 0.1)
				(type default)
			)
			(layer "F.Fab")
		)
		(fp_line
			(start -0.12065 -0.2794)
			(end 0.12065 -0.2794)
			(stroke
				(width 0.1)
				(type default)
			)
			(layer "F.Fab")
		)
		(fp_line
			(start 0.12065 -0.2794)
			(end 0.12065 -0.3048)
			(stroke
				(width 0.1)
				(type default)
			)
			(layer "F.Fab")
		)
		(fp_line
			(start 0.12065 -0.3048)
			(end 0.67945 -0.3048)
			(stroke
				(width 0.1)
				(type default)
			)
			(layer "F.Fab")
		)
		(fp_line
			(start 0.67945 -0.3048)
			(end 0.67945 0.3048)
			(stroke
				(width 0.1)
				(type default)
			)
			(layer "F.Fab")
		)
		(fp_line
			(start -0.67945 -0.305054)
			(end -0.12065 -0.305054)
			(stroke
				(width 0.1)
				(type default)
			)
			(layer "F.Fab")
		)
		(fp_line
			(start -0.12065 -0.305054)
			(end -0.12065 -0.2794)
			(stroke
				(width 0.1)
				(type default)
			)
			(layer "F.Fab")
		)
		(pad "1" smd circle
			(at -0.40005 0 270)
			(size 0 0)
			(layers "F.Cu" "F.Mask" "F.Paste")
			(net "GND")
		)
		(pad "2" smd circle
			(at 0.40005 0 270)
			(size 0 0)
			(layers "F.Cu" "F.Mask" "F.Paste")
			(net "PVCCIN_CPU0_VREF")
		)
	)
	(footprint ""
		(layer "F.Cu")
		(at 366.678718 -417.14801 90)
		(property "Reference" "R4211"
			(at 0 0 90)
			(layer "F.SilkS")
			(hide yes)
			(effects
				(font
					(size 1.27 1.27)
				)
			)
		)
		(property "Value" ""
			(at 0 0 90)
			(layer "F.Fab")
			(effects
				(font
					(size 1.27 1.27)
				)
			)
		)
		(duplicate_pad_numbers_are_jumpers no)
		(fp_line
			(start 0.7874 -0.4064)
			(end 0.7874 0.4064)
			(stroke
				(width 0.1524)
				(type default)
			)
			(layer "F.SilkS")
		)
		(fp_line
			(start -0.7874 -0.4064)
			(end 0.7874 -0.4064)
			(stroke
				(width 0.1524)
				(type default)
			)
			(layer "F.SilkS")
		)
		(fp_line
			(start 0.7874 0.4064)
			(end -0.7874 0.4064)
			(stroke
				(width 0.1524)
				(type default)
			)
			(layer "F.SilkS")
		)
		(fp_line
			(start -0.7874 0.4064)
			(end -0.7874 -0.4064)
			(stroke
				(width 0.1524)
				(type default)
			)
			(layer "F.SilkS")
		)
		(fp_line
			(start -0.12065 -0.305054)
			(end -0.12065 -0.2794)
			(stroke
				(width 0.1)
				(type default)
			)
			(layer "F.Fab")
		)
		(fp_line
			(start -0.67945 -0.305054)
			(end -0.12065 -0.305054)
			(stroke
				(width 0.1)
				(type default)
			)
			(layer "F.Fab")
		)
		(fp_line
			(start 0.67945 -0.3048)
			(end 0.67945 0.3048)
			(stroke
				(width 0.1)
				(type default)
			)
			(layer "F.Fab")
		)
		(fp_line
			(start 0.12065 -0.3048)
			(end 0.67945 -0.3048)
			(stroke
				(width 0.1)
				(type default)
			)
			(layer "F.Fab")
		)
		(fp_line
			(start 0.12065 -0.2794)
			(end 0.12065 -0.3048)
			(stroke
				(width 0.1)
				(type default)
			)
			(layer "F.Fab")
		)
		(fp_line
			(start -0.12065 -0.2794)
			(end 0.12065 -0.2794)
			(stroke
				(width 0.1)
				(type default)
			)
			(layer "F.Fab")
		)
		(fp_line
			(start 0.120396 0.2794)
			(end -0.12065 0.2794)
			(stroke
				(width 0.1)
				(type default)
			)
			(layer "F.Fab")
		)
		(fp_line
			(start -0.12065 0.2794)
			(end -0.12065 0.3048)
			(stroke
				(width 0.1)
				(type default)
			)
			(layer "F.Fab")
		)
		(fp_line
			(start 0.67945 0.3048)
			(end 0.120396 0.3048)
			(stroke
				(width 0.1)
				(type default)
			)
			(layer "F.Fab")
		)
		(fp_line
			(start 0.120396 0.3048)
			(end 0.120396 0.2794)
			(stroke
				(width 0.1)
				(type default)
			)
			(layer "F.Fab")
		)
		(fp_line
			(start -0.12065 0.3048)
			(end -0.67945 0.3048)
			(stroke
				(width 0.1)
				(type default)
			)
			(layer "F.Fab")
		)
		(fp_line
			(start -0.67945 0.3048)
			(end -0.67945 -0.305054)
			(stroke
				(width 0.1)
				(type default)
			)
			(layer "F.Fab")
		)
		(pad "1" smd circle
			(at -0.40005 0 90)
			(size 0 0)
			(layers "F.Cu" "F.Mask" "F.Paste")
			(net "P3V3_AUX")
		)
		(pad "2" smd circle
			(at 0.40005 0 90)
			(size 0 0)
			(layers "F.Cu" "F.Mask" "F.Paste")
			(net "FM_THERMAL_ALERT_N")
		)
	)
	(footprint ""
		(layer "F.Cu")
		(at 126.67488 -92.674948 -90)
		(property "Reference" "R4400"
			(at 0 0 270)
			(layer "F.SilkS")
			(hide yes)
			(effects
				(font
					(size 1.27 1.27)
				)
			)
		)
		(property "Value" ""
			(at 0 0 270)
			(layer "F.Fab")
			(effects
				(font
					(size 1.27 1.27)
				)
			)
		)
		(duplicate_pad_numbers_are_jumpers no)
		(fp_line
			(start -0.7874 0.4064)
			(end -0.7874 -0.4064)
			(stroke
				(width 0.1524)
				(type default)
			)
			(layer "F.SilkS")
		)
		(fp_line
			(start 0.7874 0.4064)
			(end -0.7874 0.4064)
			(stroke
				(width 0.1524)
				(type default)
			)
			(layer "F.SilkS")
		)
		(fp_line
			(start -0.7874 -0.4064)
			(end 0.7874 -0.4064)
			(stroke
				(width 0.1524)
				(type default)
			)
			(layer "F.SilkS")
		)
		(fp_line
			(start 0.7874 -0.4064)
			(end 0.7874 0.4064)
			(stroke
				(width 0.1524)
				(type default)
			)
			(layer "F.SilkS")
		)
		(fp_line
			(start -0.67945 0.3048)
			(end -0.67945 -0.305054)
			(stroke
				(width 0.1)
				(type default)
			)
			(layer "F.Fab")
		)
		(fp_line
			(start -0.12065 0.3048)
			(end -0.67945 0.3048)
			(stroke
				(width 0.1)
				(type default)
			)
			(layer "F.Fab")
		)
		(fp_line
			(start 0.120396 0.3048)
			(end 0.120396 0.2794)
			(stroke
				(width 0.1)
				(type default)
			)
			(layer "F.Fab")
		)
		(fp_line
			(start 0.67945 0.3048)
			(end 0.120396 0.3048)
			(stroke
				(width 0.1)
				(type default)
			)
			(layer "F.Fab")
		)
		(fp_line
			(start -0.12065 0.2794)
			(end -0.12065 0.3048)
			(stroke
				(width 0.1)
				(type default)
			)
			(layer "F.Fab")
		)
		(fp_line
			(start 0.120396 0.2794)
			(end -0.12065 0.2794)
			(stroke
				(width 0.1)
				(type default)
			)
			(layer "F.Fab")
		)
		(fp_line
			(start -0.12065 -0.2794)
			(end 0.12065 -0.2794)
			(stroke
				(width 0.1)
				(type default)
			)
			(layer "F.Fab")
		)
		(fp_line
			(start 0.12065 -0.2794)
			(end 0.12065 -0.3048)
			(stroke
				(width 0.1)
				(type default)
			)
			(layer "F.Fab")
		)
		(fp_line
			(start 0.12065 -0.3048)
			(end 0.67945 -0.3048)
			(stroke
				(width 0.1)
				(type default)
			)
			(layer "F.Fab")
		)
		(fp_line
			(start 0.67945 -0.3048)
			(end 0.67945 0.3048)
			(stroke
				(width 0.1)
				(type default)
			)
			(layer "F.Fab")
		)
		(fp_line
			(start -0.67945 -0.305054)
			(end -0.12065 -0.305054)
			(stroke
				(width 0.1)
				(type default)
			)
			(layer "F.Fab")
		)
		(fp_line
			(start -0.12065 -0.305054)
			(end -0.12065 -0.2794)
			(stroke
				(width 0.1)
				(type default)
			)
			(layer "F.Fab")
		)
		(pad "1" smd circle
			(at -0.40005 0 270)
			(size 0 0)
			(layers "F.Cu" "F.Mask" "F.Paste")
			(net "H_CPU1_THERMTRIP_VT_N")
		)
		(pad "2" smd circle
			(at 0.40005 0 270)
			(size 0 0)
			(layers "F.Cu" "F.Mask" "F.Paste")
			(net "H_CPU1_THERMTRIP_LVC1_N")
		)
	)
	(footprint ""
		(layer "F.Cu")
		(at 204.724 -92.6338 90)
		(property "Reference" "R4774"
			(at 0 0 90)
			(layer "F.SilkS")
			(hide yes)
			(effects
				(font
					(size 1.27 1.27)
				)
			)
		)
		(property "Value" ""
			(at 0 0 90)
			(layer "F.Fab")
			(effects
				(font
					(size 1.27 1.27)
				)
			)
		)
		(duplicate_pad_numbers_are_jumpers no)
		(fp_line
			(start 0.7874 -0.4064)
			(end 0.7874 0.4064)
			(stroke
				(width 0.1524)
				(type default)
			)
			(layer "F.SilkS")
		)
		(fp_line
			(start -0.7874 -0.4064)
			(end 0.7874 -0.4064)
			(stroke
				(width 0.1524)
				(type default)
			)
			(layer "F.SilkS")
		)
		(fp_line
			(start 0.7874 0.4064)
			(end -0.7874 0.4064)
			(stroke
				(width 0.1524)
				(type default)
			)
			(layer "F.SilkS")
		)
		(fp_line
			(start -0.7874 0.4064)
			(end -0.7874 -0.4064)
			(stroke
				(width 0.1524)
				(type default)
			)
			(layer "F.SilkS")
		)
		(fp_line
			(start -0.12065 -0.305054)
			(end -0.12065 -0.2794)
			(stroke
				(width 0.1)
				(type default)
			)
			(layer "F.Fab")
		)
		(fp_line
			(start -0.67945 -0.305054)
			(end -0.12065 -0.305054)
			(stroke
				(width 0.1)
				(type default)
			)
			(layer "F.Fab")
		)
		(fp_line
			(start 0.67945 -0.3048)
			(end 0.67945 0.3048)
			(stroke
				(width 0.1)
				(type default)
			)
			(layer "F.Fab")
		)
		(fp_line
			(start 0.12065 -0.3048)
			(end 0.67945 -0.3048)
			(stroke
				(width 0.1)
				(type default)
			)
			(layer "F.Fab")
		)
		(fp_line
			(start 0.12065 -0.2794)
			(end 0.12065 -0.3048)
			(stroke
				(width 0.1)
				(type default)
			)
			(layer "F.Fab")
		)
		(fp_line
			(start -0.12065 -0.2794)
			(end 0.12065 -0.2794)
			(stroke
				(width 0.1)
				(type default)
			)
			(layer "F.Fab")
		)
		(fp_line
			(start 0.120396 0.2794)
			(end -0.12065 0.2794)
			(stroke
				(width 0.1)
				(type default)
			)
			(layer "F.Fab")
		)
		(fp_line
			(start -0.12065 0.2794)
			(end -0.12065 0.3048)
			(stroke
				(width 0.1)
				(type default)
			)
			(layer "F.Fab")
		)
		(fp_line
			(start 0.67945 0.3048)
			(end 0.120396 0.3048)
			(stroke
				(width 0.1)
				(type default)
			)
			(layer "F.Fab")
		)
		(fp_line
			(start 0.120396 0.3048)
			(end 0.120396 0.2794)
			(stroke
				(width 0.1)
				(type default)
			)
			(layer "F.Fab")
		)
		(fp_line
			(start -0.12065 0.3048)
			(end -0.67945 0.3048)
			(stroke
				(width 0.1)
				(type default)
			)
			(layer "F.Fab")
		)
		(fp_line
			(start -0.67945 0.3048)
			(end -0.67945 -0.305054)
			(stroke
				(width 0.1)
				(type default)
			)
			(layer "F.Fab")
		)
		(pad "1" smd circle
			(at -0.40005 0 90)
			(size 0 0)
			(layers "F.Cu" "F.Mask" "F.Paste")
			(net "P12V_AUX")
		)
		(pad "2" smd circle
			(at 0.40005 0 90)
			(size 0 0)
			(layers "F.Cu" "F.Mask" "F.Paste")
			(net "P12V_AUX_UV_ADR_TRIGGER")
		)
	)
)
